(kicad_pcb
	(version 20241229)
	(generator "pcbnew")
	(generator_version "9.0")
	(general
		(thickness 1.6642)
		(legacy_teardrops no)
	)
	(paper "A3")
	(title_block
		(title "PolarFire SoM")
		(date "2025-07-22")
		(rev "1.1.4")
		(company "Antmicro Ltd")
		(comment 1 "www.antmicro.com")
		(comment 9 "footprints 20-25 of 470")
	)
	(layers
		(0 "F.Cu" mixed)
		(4 "In1.Cu" power)
		(6 "In2.Cu" signal)
		(8 "In3.Cu" power)
		(10 "In4.Cu" signal)
		(12 "In5.Cu" power)
		(14 "In6.Cu" power)
		(16 "In7.Cu" signal)
		(18 "In8.Cu" power)
		(20 "In9.Cu" signal)
		(22 "In10.Cu" power)
		(24 "In11.Cu" signal)
		(26 "In12.Cu" signal)
		(2 "B.Cu" mixed)
		(9 "F.Adhes" user "F.Adhesive")
		(11 "B.Adhes" user "B.Adhesive")
		(13 "F.Paste" user)
		(15 "B.Paste" user)
		(5 "F.SilkS" user "F.Silkscreen")
		(7 "B.SilkS" user "B.Silkscreen")
		(1 "F.Mask" user)
		(3 "B.Mask" user)
		(17 "Dwgs.User" user "User.Drawings")
		(19 "Cmts.User" user "User.Comments")
		(21 "Eco1.User" user "User.Eco1")
		(23 "Eco2.User" user "User.Eco2")
		(25 "Edge.Cuts" user)
		(27 "Margin" user)
		(31 "F.CrtYd" user "F.Courtyard")
		(29 "B.CrtYd" user "B.Courtyard")
		(35 "F.Fab" user)
		(33 "B.Fab" user)
	)
	(footprint "antmicro-footprints:C_0402_1005Metric"
		(layer "F.Cu")
		(at 180.7 138.3175 -90)
		(descr "Capacitor SMD 0402")
		(tags "capacitor SMD 0402")
		(property "Reference" "C93"
			(at -2.2275 -6.79 180)
			(layer "F.SilkS")
			(effects
				(font
					(size 0.7 0.7)
					(thickness 0.15)
				)
				(justify right bottom)
			)
		)
		(property "Value" "C_10u_10V_0402"
			(at -1.022927 2.155213 90)
			(layer "F.Fab")
			(hide yes)
			(effects
				(font
					(size 0.7 0.7)
					(thickness 0.15)
				)
				(justify right bottom)
			)
		)
		(property "Datasheet" "https://www.murata.com/products/productdetail?partno=GRM155R61A106ME11%23"
			(at 0 0 270)
			(layer "F.Fab")
			(hide yes)
			(effects
				(font
					(size 1.27 1.27)
					(thickness 0.15)
				)
			)
		)
		(property "Description" "Multilayer Ceramic Capacitors MLCC - SMD/SMT 10 uF 10 VDC 20% 0402 X5R"
			(at 0 0 270)
			(layer "F.Fab")
			(hide yes)
			(effects
				(font
					(size 1.27 1.27)
					(thickness 0.15)
				)
			)
		)
		(property "Author" "Antmicro"
			(at 42.3825 319.0175 0)
			(layer "F.Fab")
			(hide yes)
			(effects
				(font
					(size 1 1)
					(thickness 0.15)
				)
			)
		)
		(property "Dielectric" "X5R"
			(at 42.3825 319.0175 0)
			(layer "F.Fab")
			(hide yes)
			(effects
				(font
					(size 1 1)
					(thickness 0.15)
				)
			)
		)
		(property "License" "Apache-2.0"
			(at 42.3825 319.0175 0)
			(layer "F.Fab")
			(hide yes)
			(effects
				(font
					(size 1 1)
					(thickness 0.15)
				)
			)
		)
		(property "MPN" "GRM155R61A106ME11D"
			(at 42.3825 319.0175 0)
			(layer "F.Fab")
			(hide yes)
			(effects
				(font
					(size 1 1)
					(thickness 0.15)
				)
			)
		)
		(property "Manufacturer" "Murata"
			(at 42.3825 319.0175 0)
			(layer "F.Fab")
			(hide yes)
			(effects
				(font
					(size 1 1)
					(thickness 0.15)
				)
			)
		)
		(property "Public" ""
			(at 42.3825 319.0175 0)
			(layer "F.Fab")
			(hide yes)
			(effects
				(font
					(size 1 1)
					(thickness 0.15)
				)
			)
		)
		(property "Val" "10u"
			(at 42.3825 319.0175 0)
			(layer "F.Fab")
			(hide yes)
			(effects
				(font
					(size 1 1)
					(thickness 0.15)
				)
			)
		)
		(property "Voltage" "10V"
			(at 42.3825 319.0175 0)
			(layer "F.Fab")
			(hide yes)
			(effects
				(font
					(size 1 1)
					(thickness 0.15)
				)
			)
		)
		(sheetname "/Supply/")
		(sheetfile "supply.kicad_sch")
		(attr smd)
		(fp_rect
			(start -0.925 -0.47)
			(end 0.925 0.47)
			(stroke
				(width 0.05)
				(type default)
			)
			(fill no)
			(layer "F.CrtYd")
		)
		(fp_line
			(start -0.494 0.248)
			(end -0.494 -0.25)
			(stroke
				(width 0.15)
				(type solid)
			)
			(layer "F.Fab")
		)
		(fp_line
			(start 0.504 0.248)
			(end -0.494 0.248)
			(stroke
				(width 0.15)
				(type solid)
			)
			(layer "F.Fab")
		)
		(fp_line
			(start -0.494 -0.25)
			(end 0.504 -0.25)
			(stroke
				(width 0.15)
				(type solid)
			)
			(layer "F.Fab")
		)
		(fp_line
			(start 0.504 -0.25)
			(end 0.504 0.248)
			(stroke
				(width 0.15)
				(type solid)
			)
			(layer "F.Fab")
		)
		(fp_text user "${REFERENCE}"
			(at -0.939 4.599 270)
			(layer "F.Fab")
			(effects
				(font
					(size 0.7 0.7)
					(thickness 0.15)
				)
				(justify left bottom)
			)
		)
		(fp_text user "Author: Antmicro"
			(at -0.939 3.399 270)
			(layer "F.Fab")
			(effects
				(font
					(size 0.7 0.7)
					(thickness 0.15)
				)
				(justify left bottom)
			)
		)
		(fp_text user "License: Apache-2.0"
			(at -0.939 5.799 270)
			(layer "F.Fab")
			(effects
				(font
					(size 0.7 0.7)
					(thickness 0.15)
				)
				(justify left bottom)
			)
		)
		(pad "1" smd roundrect
			(at -0.48 0 270)
			(size 0.59 0.64)
			(layers "F.Cu" "F.Mask" "F.Paste")
			(roundrect_rratio 0.25)
			(net 417 "GND")
			(pintype "passive")
		)
		(pad "2" smd roundrect
			(at 0.48 0 270)
			(size 0.59 0.64)
			(layers "F.Cu" "F.Mask" "F.Paste")
			(roundrect_rratio 0.25)
			(net 90 "+5V")
			(pintype "passive")
		)
	)
	(footprint "antmicro-footprints:TP_SMD_0.75mm"
		(layer "F.Cu")
		(at 222.68 139.72)
		(property "Reference" "TP2"
			(at 0 -0.6 0)
			(layer "F.SilkS")
			(hide yes)
			(effects
				(font
					(size 0.7 0.7)
					(thickness 0.15)
				)
				(justify left bottom)
			)
		)
		(property "Value" "TP_0.75mm_SMD"
			(at 0 1.2 0)
			(layer "F.Fab")
			(hide yes)
			(effects
				(font
					(size 0.7 0.7)
					(thickness 0.15)
				)
				(justify left bottom)
			)
		)
		(property "Description" "SMT test point"
			(at 0 0 0)
			(layer "F.Fab")
			(hide yes)
			(effects
				(font
					(size 1.27 1.27)
					(thickness 0.15)
				)
			)
		)
		(property "Author" "Antmicro"
			(at 0 0 0)
			(layer "F.Fab")
			(hide yes)
			(effects
				(font
					(size 1 1)
					(thickness 0.15)
				)
			)
		)
		(property "License" "Apache-2.0"
			(at 0 0 0)
			(layer "F.Fab")
			(hide yes)
			(effects
				(font
					(size 1 1)
					(thickness 0.15)
				)
			)
		)
		(property "MPN" ""
			(at 0 0 0)
			(layer "F.Fab")
			(hide yes)
			(effects
				(font
					(size 1 1)
					(thickness 0.15)
				)
			)
		)
		(property "Manufacturer" ""
			(at 0 0 0)
			(layer "F.Fab")
			(hide yes)
			(effects
				(font
					(size 1 1)
					(thickness 0.15)
				)
			)
		)
		(property "Public" "False"
			(at 0 0 0)
			(layer "F.Fab")
			(hide yes)
			(effects
				(font
					(size 1 1)
					(thickness 0.15)
				)
			)
		)
		(sheetname "/WiFi_Bluetooth/")
		(sheetfile "wifi_bt.kicad_sch")
		(attr exclude_from_pos_files exclude_from_bom)
		(fp_circle
			(center 0 0)
			(end 0.475 0)
			(stroke
				(width 0.05)
				(type default)
			)
			(fill no)
			(layer "F.CrtYd")
		)
		(fp_text user "License: Apache-2.0"
			(at -0.4 5.101 0)
			(layer "F.Fab")
			(effects
				(font
					(size 0.7 0.7)
					(thickness 0.15)
				)
				(justify left bottom)
			)
		)
		(fp_text user "Author: Antmicro"
			(at -0.4 3.901 0)
			(layer "F.Fab")
			(effects
				(font
					(size 0.7 0.7)
					(thickness 0.15)
				)
				(justify left bottom)
			)
		)
		(fp_text user "${REFERENCE}"
			(at -0.4 2.7 0)
			(layer "F.Fab")
			(effects
				(font
					(size 0.7 0.7)
					(thickness 0.15)
				)
				(justify left bottom)
			)
		)
		(pad "1" smd circle
			(at 0 0)
			(size 0.75 0.75)
			(layers "F.Cu" "F.Mask")
			(net 620 "Net-(U26A-RF_SW_CTRL_0)")
			(pinfunction "1")
			(pintype "passive")
		)
	)
	(footprint "antmicro-footprints:C_0402_1005Metric"
		(layer "F.Cu")
		(at 198.3 145.43 180)
		(descr "Capacitor SMD 0402")
		(tags "capacitor SMD 0402")
		(property "Reference" "C2"
			(at -1.31 -0.27 270)
			(layer "F.SilkS")
			(effects
				(font
					(size 0.7 0.7)
					(thickness 0.15)
				)
				(justify right bottom)
			)
		)
		(property "Value" "C_100n_0402"
			(at -1.022927 2.155213 0)
			(layer "F.Fab")
			(hide yes)
			(effects
				(font
					(size 0.7 0.7)
					(thickness 0.15)
				)
				(justify right bottom)
			)
		)
		(property "Datasheet" "https://www.murata.com/products/productdetail?partno=GRM155R61H104KE14%23"
			(at 0 0 180)
			(layer "F.Fab")
			(hide yes)
			(effects
				(font
					(size 1.27 1.27)
					(thickness 0.15)
				)
			)
		)
		(property "Description" "SMD Multilayer Ceramic Capacitor, 0.1 µF, 50 V, 0402 [1005 Metric], ± 10%, X5R, GRM Series"
			(at 0 0 180)
			(layer "F.Fab")
			(hide yes)
			(effects
				(font
					(size 1.27 1.27)
					(thickness 0.15)
				)
			)
		)
		(property "Author" "Antmicro"
			(at 396.6 290.86 0)
			(layer "F.Fab")
			(hide yes)
			(effects
				(font
					(size 1 1)
					(thickness 0.15)
				)
			)
		)
		(property "Dielectric" "X5R"
			(at 396.6 290.86 0)
			(layer "F.Fab")
			(hide yes)
			(effects
				(font
					(size 1 1)
					(thickness 0.15)
				)
			)
		)
		(property "License" "Apache-2.0"
			(at 396.6 290.86 0)
			(layer "F.Fab")
			(hide yes)
			(effects
				(font
					(size 1 1)
					(thickness 0.15)
				)
			)
		)
		(property "MPN" "GRM155R61H104KE14D"
			(at 396.6 290.86 0)
			(layer "F.Fab")
			(hide yes)
			(effects
				(font
					(size 1 1)
					(thickness 0.15)
				)
			)
		)
		(property "Manufacturer" "Murata"
			(at 396.6 290.86 0)
			(layer "F.Fab")
			(hide yes)
			(effects
				(font
					(size 1 1)
					(thickness 0.15)
				)
			)
		)
		(property "Public" ""
			(at 396.6 290.86 0)
			(layer "F.Fab")
			(hide yes)
			(effects
				(font
					(size 1 1)
					(thickness 0.15)
				)
			)
		)
		(property "Val" "100n"
			(at 396.6 290.86 0)
			(layer "F.Fab")
			(hide yes)
			(effects
				(font
					(size 1 1)
					(thickness 0.15)
				)
			)
		)
		(property "Voltage" "50V"
			(at 396.6 290.86 0)
			(layer "F.Fab")
			(hide yes)
			(effects
				(font
					(size 1 1)
					(thickness 0.15)
				)
			)
		)
		(sheetname "/FPGA HSIO/")
		(sheetfile "fpga-hsio.kicad_sch")
		(attr smd)
		(fp_rect
			(start -0.925 -0.47)
			(end 0.925 0.47)
			(stroke
				(width 0.05)
				(type default)
			)
			(fill no)
			(layer "F.CrtYd")
		)
		(fp_line
			(start 0.504 0.248)
			(end -0.494 0.248)
			(stroke
				(width 0.15)
				(type solid)
			)
			(layer "F.Fab")
		)
		(fp_line
			(start 0.504 -0.25)
			(end 0.504 0.248)
			(stroke
				(width 0.15)
				(type solid)
			)
			(layer "F.Fab")
		)
		(fp_line
			(start -0.494 0.248)
			(end -0.494 -0.25)
			(stroke
				(width 0.15)
				(type solid)
			)
			(layer "F.Fab")
		)
		(fp_line
			(start -0.494 -0.25)
			(end 0.504 -0.25)
			(stroke
				(width 0.15)
				(type solid)
			)
			(layer "F.Fab")
		)
		(fp_text user "${REFERENCE}"
			(at -0.939 4.599 180)
			(layer "F.Fab")
			(effects
				(font
					(size 0.7 0.7)
					(thickness 0.15)
				)
				(justify left bottom)
			)
		)
		(fp_text user "License: Apache-2.0"
			(at -0.939 5.799 180)
			(layer "F.Fab")
			(effects
				(font
					(size 0.7 0.7)
					(thickness 0.15)
				)
				(justify left bottom)
			)
		)
		(fp_text user "Author: Antmicro"
			(at -0.939 3.399 180)
			(layer "F.Fab")
			(effects
				(font
					(size 0.7 0.7)
					(thickness 0.15)
				)
				(justify left bottom)
			)
		)
		(pad "1" smd roundrect
			(at -0.48 0 180)
			(size 0.59 0.64)
			(layers "F.Cu" "F.Mask" "F.Paste")
			(roundrect_rratio 0.25)
			(net 417 "GND")
			(pintype "passive")
		)
		(pad "2" smd roundrect
			(at 0.48 0 180)
			(size 0.59 0.64)
			(layers "F.Cu" "F.Mask" "F.Paste")
			(roundrect_rratio 0.25)
			(net 48 "+1V8")
			(pintype "passive")
		)
	)
	(footprint "antmicro-footprints:MP_NPTH_Drill2.7mm"
		(locked yes)
		(layer "F.Cu")
		(at 226.01377 152.33277)
		(property "Reference" "MP3"
			(at 0 -1.8 0)
			(layer "F.SilkS")
			(hide yes)
			(effects
				(font
					(size 0.7 0.7)
					(thickness 0.15)
				)
				(justify left bottom)
			)
		)
		(property "Value" "MP_NPTH_Drill2.7mm"
			(at 0 2.3 0)
			(layer "F.Fab")
			(hide yes)
			(effects
				(font
					(size 0.7 0.7)
					(thickness 0.15)
				)
				(justify left bottom)
			)
		)
		(property "Description" "Mechanical part"
			(at 0 0 0)
			(layer "F.Fab")
			(hide yes)
			(effects
				(font
					(size 1.27 1.27)
					(thickness 0.15)
				)
			)
		)
		(property "Author" "Antmicro"
			(at 0 0 0)
			(layer "F.Fab")
			(hide yes)
			(effects
				(font
					(size 1 1)
					(thickness 0.15)
				)
			)
		)
		(property "License" "Apache-2.0"
			(at 0 0 0)
			(layer "F.Fab")
			(hide yes)
			(effects
				(font
					(size 1 1)
					(thickness 0.15)
				)
			)
		)
		(property "exclude_from_bom" ""
			(at 0 0 0)
			(layer "F.Fab")
			(hide yes)
			(effects
				(font
					(size 1 1)
					(thickness 0.15)
				)
			)
		)
		(sheetfile "polarfire-som.kicad_sch")
		(attr board_only exclude_from_pos_files exclude_from_bom)
		(fp_circle
			(center 0 0)
			(end 1.45 0)
			(stroke
				(width 0.05)
				(type default)
			)
			(fill no)
			(layer "F.CrtYd")
		)
		(fp_text user "Author: Antmicro"
			(at 0 5.95 0)
			(layer "F.Fab")
			(effects
				(font
					(size 0.7 0.7)
					(thickness 0.15)
				)
				(justify left bottom)
			)
		)
		(fp_text user "${REFERENCE}"
			(at 0 4.749 0)
			(layer "F.Fab")
			(effects
				(font
					(size 0.7 0.7)
					(thickness 0.15)
				)
				(justify left bottom)
			)
		)
		(fp_text user "License: Apache-2.0"
			(at 0 7.15 0)
			(layer "F.Fab")
			(effects
				(font
					(size 0.7 0.7)
					(thickness 0.15)
				)
				(justify left bottom)
			)
		)
		(pad "" np_thru_hole circle
			(at 0 0)
			(size 2.7 2.7)
			(drill 2.7)
			(layers "F&B.Cu" "*.Mask")
		)
	)
	(footprint "antmicro-footprints:C_0402_1005Metric"
		(layer "F.Cu")
		(at 185.684904 147.897281 -90)
		(descr "Capacitor SMD 0402")
		(tags "capacitor SMD 0402")
		(property "Reference" "C97"
			(at 5.06272 -7.315096 180)
			(layer "F.SilkS")
			(effects
				(font
					(size 0.7 0.7)
					(thickness 0.15)
				)
				(justify right bottom)
			)
		)
		(property "Value" "C_22u_0402"
			(at -1.022927 2.155213 90)
			(layer "F.Fab")
			(hide yes)
			(effects
				(font
					(size 0.7 0.7)
					(thickness 0.15)
				)
				(justify right bottom)
			)
		)
		(property "Datasheet" "https://www.murata.com/products/productdetail?partno=GRM158R60J226ME01%23"
			(at 0 0 270)
			(layer "F.Fab")
			(hide yes)
			(effects
				(font
					(size 1.27 1.27)
					(thickness 0.15)
				)
			)
		)
		(property "Description" "SMD Multilayer Ceramic Capacitor, 22 uF, 4 V, 0402 [1005 Metric], X6S"
			(at 0 0 270)
			(layer "F.Fab")
			(hide yes)
			(effects
				(font
					(size 1.27 1.27)
					(thickness 0.15)
				)
			)
		)
		(property "Author" "Antmicro"
			(at 37.787623 333.582185 0)
			(layer "F.Fab")
			(hide yes)
			(effects
				(font
					(size 1 1)
					(thickness 0.15)
				)
			)
		)
		(property "Dielectric" ""
			(at 37.787623 333.582185 0)
			(layer "F.Fab")
			(hide yes)
			(effects
				(font
					(size 1 1)
					(thickness 0.15)
				)
			)
		)
		(property "License" "Apache-2.0"
			(at 37.787623 333.582185 0)
			(layer "F.Fab")
			(hide yes)
			(effects
				(font
					(size 1 1)
					(thickness 0.15)
				)
			)
		)
		(property "MPN" "GRM158R60J226ME01D"
			(at 37.787623 333.582185 0)
			(layer "F.Fab")
			(hide yes)
			(effects
				(font
					(size 1 1)
					(thickness 0.15)
				)
			)
		)
		(property "Manufacturer" "Murata"
			(at 37.787623 333.582185 0)
			(layer "F.Fab")
			(hide yes)
			(effects
				(font
					(size 1 1)
					(thickness 0.15)
				)
			)
		)
		(property "Public" ""
			(at 37.787623 333.582185 0)
			(layer "F.Fab")
			(hide yes)
			(effects
				(font
					(size 1 1)
					(thickness 0.15)
				)
			)
		)
		(property "Val" "22u"
			(at 37.787623 333.582185 0)
			(layer "F.Fab")
			(hide yes)
			(effects
				(font
					(size 1 1)
					(thickness 0.15)
				)
			)
		)
		(property "Voltage" ""
			(at 37.787623 333.582185 0)
			(layer "F.Fab")
			(hide yes)
			(effects
				(font
					(size 1 1)
					(thickness 0.15)
				)
			)
		)
		(sheetname "/Supply/")
		(sheetfile "supply.kicad_sch")
		(attr smd)
		(fp_rect
			(start -0.925 -0.47)
			(end 0.925 0.47)
			(stroke
				(width 0.05)
				(type default)
			)
			(fill no)
			(layer "F.CrtYd")
		)
		(fp_line
			(start -0.494 0.248)
			(end -0.494 -0.25)
			(stroke
				(width 0.15)
				(type solid)
			)
			(layer "F.Fab")
		)
		(fp_line
			(start 0.504 0.248)
			(end -0.494 0.248)
			(stroke
				(width 0.15)
				(type solid)
			)
			(layer "F.Fab")
		)
		(fp_line
			(start -0.494 -0.25)
			(end 0.504 -0.25)
			(stroke
				(width 0.15)
				(type solid)
			)
			(layer "F.Fab")
		)
		(fp_line
			(start 0.504 -0.25)
			(end 0.504 0.248)
			(stroke
				(width 0.15)
				(type solid)
			)
			(layer "F.Fab")
		)
		(fp_text user "License: Apache-2.0"
			(at -0.939 5.799 270)
			(layer "F.Fab")
			(effects
				(font
					(size 0.7 0.7)
					(thickness 0.15)
				)
				(justify left bottom)
			)
		)
		(fp_text user "Author: Antmicro"
			(at -0.939 3.399 270)
			(layer "F.Fab")
			(effects
				(font
					(size 0.7 0.7)
					(thickness 0.15)
				)
				(justify left bottom)
			)
		)
		(fp_text user "${REFERENCE}"
			(at -0.939 4.599 270)
			(layer "F.Fab")
			(effects
				(font
					(size 0.7 0.7)
					(thickness 0.15)
				)
				(justify left bottom)
			)
		)
		(pad "1" smd roundrect
			(at -0.48 0 270)
			(size 0.59 0.64)
			(layers "F.Cu" "F.Mask" "F.Paste")
			(roundrect_rratio 0.25)
			(net 417 "GND")
			(pintype "passive")
		)
		(pad "2" smd roundrect
			(at 0.48 0 270)
			(size 0.59 0.64)
			(layers "F.Cu" "F.Mask" "F.Paste")
			(roundrect_rratio 0.25)
			(net 522 "/Supply/1V05_REG")
			(pintype "passive")
		)
	)
	(footprint "antmicro-footprints:TP_SMD_0.75mm"
		(layer "F.Cu")
		(at 179.45 145.3375 90)
		(property "Reference" "TP26"
			(at 0 -0.6 90)
			(layer "F.SilkS")
			(hide yes)
			(effects
				(font
					(size 0.7 0.7)
					(thickness 0.15)
				)
				(justify left bottom)
			)
		)
		(property "Value" "TP_0.75mm_SMD"
			(at 0 1.2 90)
			(layer "F.Fab")
			(hide yes)
			(effects
				(font
					(size 0.7 0.7)
					(thickness 0.15)
				)
				(justify left bottom)
			)
		)
		(property "Description" "SMT test point"
			(at 0 0 90)
			(layer "F.Fab")
			(hide yes)
			(effects
				(font
					(size 1.27 1.27)
					(thickness 0.15)
				)
			)
		)
		(property "Author" "Antmicro"
			(at 324.7875 -34.1125 0)
			(layer "F.Fab")
			(hide yes)
			(effects
				(font
					(size 1 1)
					(thickness 0.15)
				)
			)
		)
		(property "License" "Apache-2.0"
			(at 324.7875 -34.1125 0)
			(layer "F.Fab")
			(hide yes)
			(effects
				(font
					(size 1 1)
					(thickness 0.15)
				)
			)
		)
		(property "MPN" ""
			(at 324.7875 -34.1125 0)
			(layer "F.Fab")
			(hide yes)
			(effects
				(font
					(size 1 1)
					(thickness 0.15)
				)
			)
		)
		(property "Manufacturer" ""
			(at 324.7875 -34.1125 0)
			(layer "F.Fab")
			(hide yes)
			(effects
				(font
					(size 1 1)
					(thickness 0.15)
				)
			)
		)
		(property "Public" "False"
			(at 324.7875 -34.1125 0)
			(layer "F.Fab")
			(hide yes)
			(effects
				(font
					(size 1 1)
					(thickness 0.15)
				)
			)
		)
		(sheetname "/Supply/")
		(sheetfile "supply.kicad_sch")
		(attr exclude_from_pos_files exclude_from_bom)
		(fp_circle
			(center 0 0)
			(end 0.475 0)
			(stroke
				(width 0.05)
				(type default)
			)
			(fill no)
			(layer "F.CrtYd")
		)
		(fp_text user "License: Apache-2.0"
			(at -0.4 5.101 90)
			(layer "F.Fab")
			(effects
				(font
					(size 0.7 0.7)
					(thickness 0.15)
				)
				(justify left bottom)
			)
		)
		(fp_text user "${REFERENCE}"
			(at -0.4 2.7 90)
			(layer "F.Fab")
			(effects
				(font
					(size 0.7 0.7)
					(thickness 0.15)
				)
				(justify left bottom)
			)
		)
		(fp_text user "Author: Antmicro"
			(at -0.4 3.901 90)
			(layer "F.Fab")
			(effects
				(font
					(size 0.7 0.7)
					(thickness 0.15)
				)
				(justify left bottom)
			)
		)
		(pad "1" smd circle
			(at 0 0 90)
			(size 0.75 0.75)
			(layers "F.Cu" "F.Mask")
			(net 92 "/FPGA MSSIO/SUPPLY.SCL")
			(pinfunction "1")
			(pintype "passive")
		)
	)
)
